(kicad_pcb
	(version 20241229)
	(generator "pcbnew")
	(generator_version "9.0")
	(general
		(thickness 1.711)
		(legacy_teardrops no)
	)
	(paper "A4")
	(title_block
		(title "Antmicro Baseboard for Jetson AGX Thor")
		(date "2026-02-18")
		(rev "1.1.0")
		(company "Antmicro Ltd")
		(comment 1 "www.antmicro.com")
		(comment 9 "footprints 545-547 of 1170")
	)
	(layers
		(0 "F.Cu" signal)
		(4 "In1.Cu" signal)
		(6 "In2.Cu" signal)
		(8 "In3.Cu" signal)
		(10 "In4.Cu" jumper)
		(12 "In5.Cu" signal)
		(14 "In6.Cu" signal)
		(16 "In7.Cu" signal)
		(18 "In8.Cu" signal)
		(2 "B.Cu" signal)
		(9 "F.Adhes" user "F.Adhesive")
		(11 "B.Adhes" user "B.Adhesive")
		(13 "F.Paste" user)
		(15 "B.Paste" user)
		(5 "F.SilkS" user "F.Silkscreen")
		(7 "B.SilkS" user "B.Silkscreen")
		(1 "F.Mask" user)
		(3 "B.Mask" user)
		(17 "Dwgs.User" user "User.Drawings")
		(19 "Cmts.User" user "User.Comments")
		(21 "Eco1.User" user "User.Eco1")
		(23 "Eco2.User" user "User.Eco2")
		(25 "Edge.Cuts" user)
		(27 "Margin" user)
		(31 "F.CrtYd" user "F.Courtyard")
		(29 "B.CrtYd" user "B.Courtyard")
		(35 "F.Fab" user)
		(33 "B.Fab" user)
	)
	(footprint "antmicro-footprints:Vishay_PowerPAK_1212-8_Single"
		(layer "F.Cu")
		(at 216.743 68.8)
		(descr "PowerPAK 1212-8 Single")
		(tags "Vishay PowerPAK 1212-8 Single")
		(property "Reference" "Q32"
			(at 2.907 0.4 90)
			(layer "F.SilkS")
			(effects
				(font
					(size 0.7 0.7)
					(thickness 0.15)
				)
				(justify left bottom)
			)
		)
		(property "Value" "SISS05DN-T1-GE3"
			(at 0 2.7 0)
			(layer "F.Fab")
			(effects
				(font
					(size 0.7 0.7)
					(thickness 0.15)
				)
				(justify left bottom)
			)
		)
		(property "Datasheet" "https://www.vishay.com/docs/77029/siss05dn.pdf"
			(at 0 0 0)
			(layer "F.Fab")
			(hide yes)
			(effects
				(font
					(size 1.27 1.27)
					(thickness 0.15)
				)
			)
		)
		(property "Description" "Power MOSFET, P Channel, 30 V, 108 A, 0.0035 ohm, PowerPAK 1212, Surface Mount"
			(at 0 0 0)
			(layer "F.Fab")
			(hide yes)
			(effects
				(font
					(size 1.27 1.27)
					(thickness 0.15)
				)
			)
		)
		(property "MPN" "SISS05DN-T1-GE3"
			(at 0 0 0)
			(unlocked yes)
			(layer "F.Fab")
			(hide yes)
			(effects
				(font
					(size 1 1)
					(thickness 0.15)
				)
			)
		)
		(property "Manufacturer" "Vishay"
			(at 0 0 0)
			(unlocked yes)
			(layer "F.Fab")
			(hide yes)
			(effects
				(font
					(size 1 1)
					(thickness 0.15)
				)
			)
		)
		(property "Author" "Antmicro"
			(at 0 0 0)
			(unlocked yes)
			(layer "F.Fab")
			(hide yes)
			(effects
				(font
					(size 1 1)
					(thickness 0.15)
				)
			)
		)
		(property "License" "Apache-2.0"
			(at 0 0 0)
			(unlocked yes)
			(layer "F.Fab")
			(hide yes)
			(effects
				(font
					(size 1 1)
					(thickness 0.15)
				)
			)
		)
		(sheetname "/Power/")
		(sheetfile "power.kicad_sch")
		(attr smd)
		(fp_line
			(start -1.651 -1.651)
			(end -1.651 -1.317)
			(stroke
				(width 0.15)
				(type solid)
			)
			(layer "F.SilkS")
		)
		(fp_line
			(start -1.651 -1.651)
			(end 1.648 -1.651)
			(stroke
				(width 0.15)
				(type solid)
			)
			(layer "F.SilkS")
		)
		(fp_line
			(start -1.635 1.3)
			(end -1.635 1.634)
			(stroke
				(width 0.15)
				(type solid)
			)
			(layer "F.SilkS")
		)
		(fp_line
			(start -1.635 1.634)
			(end 1.634 1.634)
			(stroke
				(width 0.15)
				(type solid)
			)
			(layer "F.SilkS")
		)
		(fp_line
			(start 1.634 1.3)
			(end 1.634 1.634)
			(stroke
				(width 0.15)
				(type solid)
			)
			(layer "F.SilkS")
		)
		(fp_line
			(start 1.648 -1.651)
			(end 1.648 -1.317)
			(stroke
				(width 0.15)
				(type solid)
			)
			(layer "F.SilkS")
		)
		(fp_circle
			(center -1.9 -1.4)
			(end -1.85 -1.4)
			(stroke
				(width 0.15)
				(type solid)
			)
			(fill yes)
			(layer "F.SilkS")
		)
		(fp_rect
			(start -2 -1.8)
			(end 2 1.798)
			(stroke
				(width 0.05)
				(type solid)
			)
			(fill no)
			(layer "F.CrtYd")
		)
		(fp_line
			(start -1.6425 -1.4175)
			(end -1.4175 -1.6425)
			(stroke
				(width 0.15)
				(type solid)
			)
			(layer "F.Fab")
		)
		(fp_rect
			(start -1.651 -1.651)
			(end 1.648 1.648)
			(stroke
				(width 0.15)
				(type solid)
			)
			(fill no)
			(layer "F.Fab")
		)
		(fp_text user "License: Apache-2.0"
			(at -8 7.1 0)
			(layer "F.Fab")
			(effects
				(font
					(size 0.7 0.7)
					(thickness 0.15)
				)
				(justify left bottom)
			)
		)
		(fp_text user "Author: Antmicro"
			(at -8 5.9 0)
			(layer "F.Fab")
			(effects
				(font
					(size 0.7 0.7)
					(thickness 0.15)
				)
				(justify left bottom)
			)
		)
		(fp_text user "${REFERENCE}"
			(at -8 4.7 0)
			(layer "F.Fab")
			(effects
				(font
					(size 0.7 0.7)
					(thickness 0.15)
				)
				(justify left bottom)
			)
		)
		(pad "1" smd rect
			(at -1.436 -0.99)
			(size 0.99 0.405)
			(layers "F.Cu" "F.Mask" "F.Paste")
			(net 1383 "VCC_NO_OVP")
			(pinfunction "S")
			(pintype "passive")
		)
		(pad "2" smd rect
			(at -1.436 -0.332)
			(size 0.99 0.405)
			(layers "F.Cu" "F.Mask" "F.Paste")
			(net 1383 "VCC_NO_OVP")
			(pinfunction "S")
			(pintype "passive")
		)
		(pad "3" smd rect
			(at -1.436 0.33)
			(size 0.99 0.405)
			(layers "F.Cu" "F.Mask" "F.Paste")
			(net 1383 "VCC_NO_OVP")
			(pinfunction "S")
			(pintype "passive")
		)
		(pad "4" smd rect
			(at -1.436 0.988)
			(size 0.99 0.405)
			(layers "F.Cu" "F.Mask" "F.Paste")
			(net 1384 "Net-(Q32-G)")
			(pinfunction "G")
			(pintype "input")
		)
		(pad "5" smd custom
			(at 0.557 0)
			(size 1.725 2.235)
			(layers "F.Cu" "F.Mask" "F.Paste")
			(net 3 "VCC_IN")
			(pinfunction "D")
			(pintype "passive")
			(zone_connect 2)
			(options
				(clearance outline)
				(anchor rect)
			)
			(primitives
				(gr_poly
					(pts
						(xy 0.8625 0.1275) (xy 0.8625 -0.1275) (xy 1.3725 -0.1275) (xy 1.3725 -0.5325) (xy 0.8625 -0.5325)
						(xy 0.8625 -0.7875) (xy 1.3725 -0.7875) (xy 1.3725 -1.195) (xy 0.6125 -1.195) (xy 0.6125 1.195)
						(xy 1.3725 1.195) (xy 1.3725 0.7875) (xy 0.8625 0.7875) (xy 0.8625 0.5325) (xy 1.3725 0.5325)
						(xy 1.3725 0.1275)
					)
					(width 0)
					(fill yes)
				)
			)
		)
	)
	(footprint "antmicro-footprints:LED_0603_1608Metric_G"
		(layer "F.Cu")
		(at 177.5 55.32 -90)
		(descr "LED SMD 0603 Green")
		(tags "LED SMD 0603 Green")
		(property "Reference" "D63"
			(at -1.04 1.365 90)
			(layer "F.SilkS")
			(effects
				(font
					(size 0.7 0.7)
					(thickness 0.15)
				)
				(justify right top)
			)
		)
		(property "Value" "LED_G_0603_LTST-C190GKT"
			(at -0.001 1.599 90)
			(layer "F.Fab")
			(effects
				(font
					(size 0.7 0.7)
					(thickness 0.15)
				)
				(justify right top)
			)
		)
		(property "Datasheet" "https://media.digikey.com/pdf/Data%20Sheets/Lite-On%20PDFs/LTST-C190GKT.pdf"
			(at 0 0 90)
			(layer "F.Fab")
			(hide yes)
			(effects
				(font
					(size 1.27 1.27)
					(thickness 0.15)
				)
			)
		)
		(property "Description" "LED, Green, SMD, 0603, 20 mA, 2.1 V, 569 nm"
			(at 0 0 90)
			(layer "F.Fab")
			(hide yes)
			(effects
				(font
					(size 1.27 1.27)
					(thickness 0.15)
				)
			)
		)
		(property "MPN" "LTST-C190GKT"
			(at 0 0 270)
			(unlocked yes)
			(layer "F.Fab")
			(hide yes)
			(effects
				(font
					(size 1 1)
					(thickness 0.15)
				)
			)
		)
		(property "Manufacturer" "Lite-On"
			(at 0 0 270)
			(unlocked yes)
			(layer "F.Fab")
			(hide yes)
			(effects
				(font
					(size 1 1)
					(thickness 0.15)
				)
			)
		)
		(property "Author" "Antmicro"
			(at 0 0 270)
			(unlocked yes)
			(layer "F.Fab")
			(hide yes)
			(effects
				(font
					(size 1 1)
					(thickness 0.15)
				)
			)
		)
		(property "License" "Apache-2.0"
			(at 0 0 270)
			(unlocked yes)
			(layer "F.Fab")
			(hide yes)
			(effects
				(font
					(size 1 1)
					(thickness 0.15)
				)
			)
		)
		(property "Color" "Green"
			(at 0 0 270)
			(unlocked yes)
			(layer "F.Fab")
			(hide yes)
			(effects
				(font
					(size 1 1)
					(thickness 0.15)
				)
			)
		)
		(sheetname "/Power/")
		(sheetfile "power.kicad_sch")
		(attr smd)
		(fp_line
			(start 0.22 0.35)
			(end -0.22 0.35)
			(stroke
				(width 0.15)
				(type solid)
			)
			(layer "F.SilkS")
		)
		(fp_line
			(start -0.094672 0.201008)
			(end -0.094672 -0.198992)
			(stroke
				(width 0.1)
				(type solid)
			)
			(layer "F.SilkS")
		)
		(fp_line
			(start 0.105328 0.201008)
			(end -0.094672 0.001008)
			(stroke
				(width 0.1)
				(type solid)
			)
			(layer "F.SilkS")
		)
		(fp_line
			(start 0.105328 0.201008)
			(end 0.105328 -0.198992)
			(stroke
				(width 0.1)
				(type solid)
			)
			(layer "F.SilkS")
		)
		(fp_line
			(start -0.094672 0.001008)
			(end -0.24 0.001008)
			(stroke
				(width 0.1)
				(type solid)
			)
			(layer "F.SilkS")
		)
		(fp_line
			(start -0.094672 0.001008)
			(end 0.105328 -0.198992)
			(stroke
				(width 0.1)
				(type solid)
			)
			(layer "F.SilkS")
		)
		(fp_line
			(start 0.105328 0.001008)
			(end 0.24 0.001)
			(stroke
				(width 0.1)
				(type solid)
			)
			(layer "F.SilkS")
		)
		(fp_line
			(start -1.18 -0.319)
			(end -1.18 0.321)
			(stroke
				(width 0.15)
				(type solid)
			)
			(layer "F.SilkS")
		)
		(fp_line
			(start 0.22 -0.35)
			(end -0.22 -0.35)
			(stroke
				(width 0.15)
				(type solid)
			)
			(layer "F.SilkS")
		)
		(fp_rect
			(start 1.25 0.65)
			(end -1.25 -0.65)
			(stroke
				(width 0.05)
				(type solid)
			)
			(fill no)
			(layer "F.CrtYd")
		)
		(fp_line
			(start -0.199 0.2)
			(end -0.199 0.1)
			(stroke
				(width 0.15)
				(type solid)
			)
			(layer "F.Fab")
		)
		(fp_line
			(start 0.201 0.2)
			(end 0.201 0)
			(stroke
				(width 0.15)
				(type solid)
			)
			(layer "F.Fab")
		)
		(fp_line
			(start -0.199 0)
			(end -0.597 0)
			(stroke
				(width 0.15)
				(type solid)
			)
			(layer "F.Fab")
		)
		(fp_line
			(start -0.101 0)
			(end 0.201 0.2)
			(stroke
				(width 0.15)
				(type solid)
			)
			(layer "F.Fab")
		)
		(fp_line
			(start 0.201 0)
			(end 0.201 -0.202)
			(stroke
				(width 0.15)
				(type solid)
			)
			(layer "F.Fab")
		)
		(fp_line
			(start 0.599 0)
			(end 0.201 0)
			(stroke
				(width 0.15)
				(type solid)
			)
			(layer "F.Fab")
		)
		(fp_line
			(start -0.199 -0.202)
			(end -0.199 0.1)
			(stroke
				(width 0.15)
				(type solid)
			)
			(layer "F.Fab")
		)
		(fp_line
			(start 0.201 -0.202)
			(end -0.101 0)
			(stroke
				(width 0.15)
				(type solid)
			)
			(layer "F.Fab")
		)
		(fp_rect
			(start 0.848 0.4)
			(end -0.85 -0.402)
			(stroke
				(width 0.15)
				(type solid)
			)
			(fill no)
			(layer "F.Fab")
		)
		(fp_text user "License: Apache-2.0"
			(at -1.4224 3.599 90)
			(layer "F.Fab")
			(effects
				(font
					(size 0.7 0.7)
					(thickness 0.15)
				)
				(justify right top)
			)
		)
		(fp_text user "Author: Antmicro"
			(at -1.4224 4.799 90)
			(layer "F.Fab")
			(effects
				(font
					(size 0.7 0.7)
					(thickness 0.15)
				)
				(justify right top)
			)
		)
		(fp_text user "${REFERENCE}"
			(at -1.4224 5.999 90)
			(layer "F.Fab")
			(effects
				(font
					(size 0.7 0.7)
					(thickness 0.15)
				)
				(justify right top)
			)
		)
		(pad "1" smd roundrect
			(at -0.7 0 90)
			(size 0.8 1)
			(layers "F.Cu" "F.Mask" "F.Paste")
			(roundrect_rratio 0.2)
			(net 1 "GND")
			(pinfunction "C")
			(pintype "passive")
		)
		(pad "2" smd roundrect
			(at 0.7 0 90)
			(size 0.8 1)
			(layers "F.Cu" "F.Mask" "F.Paste")
			(roundrect_rratio 0.2)
			(net 46 "Net-(D63-A)")
			(pinfunction "A")
			(pintype "passive")
		)
	)
	(footprint "antmicro-footprints:LED_0603_1608Metric_G"
		(layer "F.Cu")
		(at 184.25 55.3 -90)
		(descr "LED SMD 0603 Green")
		(tags "LED SMD 0603 Green")
		(property "Reference" "D4"
			(at -0.62 1.6 90)
			(layer "F.SilkS")
			(effects
				(font
					(size 0.7 0.7)
					(thickness 0.15)
				)
				(justify right top)
			)
		)
		(property "Value" "LED_G_0603_LTST-C190GKT"
			(at -0.001 1.599 90)
			(layer "F.Fab")
			(effects
				(font
					(size 0.7 0.7)
					(thickness 0.15)
				)
				(justify right top)
			)
		)
		(property "Datasheet" "https://media.digikey.com/pdf/Data%20Sheets/Lite-On%20PDFs/LTST-C190GKT.pdf"
			(at 0 0 90)
			(layer "F.Fab")
			(hide yes)
			(effects
				(font
					(size 1.27 1.27)
					(thickness 0.15)
				)
			)
		)
		(property "Description" "LED, Green, SMD, 0603, 20 mA, 2.1 V, 569 nm"
			(at 0 0 90)
			(layer "F.Fab")
			(hide yes)
			(effects
				(font
					(size 1.27 1.27)
					(thickness 0.15)
				)
			)
		)
		(property "MPN" "LTST-C190GKT"
			(at 0 0 270)
			(unlocked yes)
			(layer "F.Fab")
			(hide yes)
			(effects
				(font
					(size 1 1)
					(thickness 0.15)
				)
			)
		)
		(property "Manufacturer" "Lite-On"
			(at 0 0 270)
			(unlocked yes)
			(layer "F.Fab")
			(hide yes)
			(effects
				(font
					(size 1 1)
					(thickness 0.15)
				)
			)
		)
		(property "Author" "Antmicro"
			(at 0 0 270)
			(unlocked yes)
			(layer "F.Fab")
			(hide yes)
			(effects
				(font
					(size 1 1)
					(thickness 0.15)
				)
			)
		)
		(property "License" "Apache-2.0"
			(at 0 0 270)
			(unlocked yes)
			(layer "F.Fab")
			(hide yes)
			(effects
				(font
					(size 1 1)
					(thickness 0.15)
				)
			)
		)
		(property "Color" "Green"
			(at 0 0 270)
			(unlocked yes)
			(layer "F.Fab")
			(hide yes)
			(effects
				(font
					(size 1 1)
					(thickness 0.15)
				)
			)
		)
		(sheetname "/Power/")
		(sheetfile "power.kicad_sch")
		(attr smd)
		(fp_line
			(start 0.22 0.35)
			(end -0.22 0.35)
			(stroke
				(width 0.15)
				(type solid)
			)
			(layer "F.SilkS")
		)
		(fp_line
			(start -0.094672 0.201008)
			(end -0.094672 -0.198992)
			(stroke
				(width 0.1)
				(type solid)
			)
			(layer "F.SilkS")
		)
		(fp_line
			(start 0.105328 0.201008)
			(end -0.094672 0.001008)
			(stroke
				(width 0.1)
				(type solid)
			)
			(layer "F.SilkS")
		)
		(fp_line
			(start 0.105328 0.201008)
			(end 0.105328 -0.198992)
			(stroke
				(width 0.1)
				(type solid)
			)
			(layer "F.SilkS")
		)
		(fp_line
			(start -0.094672 0.001008)
			(end -0.24 0.001008)
			(stroke
				(width 0.1)
				(type solid)
			)
			(layer "F.SilkS")
		)
		(fp_line
			(start -0.094672 0.001008)
			(end 0.105328 -0.198992)
			(stroke
				(width 0.1)
				(type solid)
			)
			(layer "F.SilkS")
		)
		(fp_line
			(start 0.105328 0.001008)
			(end 0.24 0.001)
			(stroke
				(width 0.1)
				(type solid)
			)
			(layer "F.SilkS")
		)
		(fp_line
			(start -1.18 -0.319)
			(end -1.18 0.321)
			(stroke
				(width 0.15)
				(type solid)
			)
			(layer "F.SilkS")
		)
		(fp_line
			(start 0.22 -0.35)
			(end -0.22 -0.35)
			(stroke
				(width 0.15)
				(type solid)
			)
			(layer "F.SilkS")
		)
		(fp_rect
			(start 1.25 0.65)
			(end -1.25 -0.65)
			(stroke
				(width 0.05)
				(type solid)
			)
			(fill no)
			(layer "F.CrtYd")
		)
		(fp_line
			(start -0.199 0.2)
			(end -0.199 0.1)
			(stroke
				(width 0.15)
				(type solid)
			)
			(layer "F.Fab")
		)
		(fp_line
			(start 0.201 0.2)
			(end 0.201 0)
			(stroke
				(width 0.15)
				(type solid)
			)
			(layer "F.Fab")
		)
		(fp_line
			(start -0.199 0)
			(end -0.597 0)
			(stroke
				(width 0.15)
				(type solid)
			)
			(layer "F.Fab")
		)
		(fp_line
			(start -0.101 0)
			(end 0.201 0.2)
			(stroke
				(width 0.15)
				(type solid)
			)
			(layer "F.Fab")
		)
		(fp_line
			(start 0.201 0)
			(end 0.201 -0.202)
			(stroke
				(width 0.15)
				(type solid)
			)
			(layer "F.Fab")
		)
		(fp_line
			(start 0.599 0)
			(end 0.201 0)
			(stroke
				(width 0.15)
				(type solid)
			)
			(layer "F.Fab")
		)
		(fp_line
			(start -0.199 -0.202)
			(end -0.199 0.1)
			(stroke
				(width 0.15)
				(type solid)
			)
			(layer "F.Fab")
		)
		(fp_line
			(start 0.201 -0.202)
			(end -0.101 0)
			(stroke
				(width 0.15)
				(type solid)
			)
			(layer "F.Fab")
		)
		(fp_rect
			(start 0.848 0.4)
			(end -0.85 -0.402)
			(stroke
				(width 0.15)
				(type solid)
			)
			(fill no)
			(layer "F.Fab")
		)
		(fp_text user "${REFERENCE}"
			(at -1.4224 5.999 90)
			(layer "F.Fab")
			(effects
				(font
					(size 0.7 0.7)
					(thickness 0.15)
				)
				(justify right top)
			)
		)
		(fp_text user "License: Apache-2.0"
			(at -1.4224 3.599 90)
			(layer "F.Fab")
			(effects
				(font
					(size 0.7 0.7)
					(thickness 0.15)
				)
				(justify right top)
			)
		)
		(fp_text user "Author: Antmicro"
			(at -1.4224 4.799 90)
			(layer "F.Fab")
			(effects
				(font
					(size 0.7 0.7)
					(thickness 0.15)
				)
				(justify right top)
			)
		)
		(pad "1" smd roundrect
			(at -0.7 0 90)
			(size 0.8 1)
			(layers "F.Cu" "F.Mask" "F.Paste")
			(roundrect_rratio 0.2)
			(net 1 "GND")
			(pinfunction "C")
			(pintype "passive")
		)
		(pad "2" smd roundrect
			(at 0.7 0 90)
			(size 0.8 1)
			(layers "F.Cu" "F.Mask" "F.Paste")
			(roundrect_rratio 0.2)
			(net 528 "Net-(D4-A)")
			(pinfunction "A")
			(pintype "passive")
		)
	)
)
